(kicad_pcb
	(version 20260206)
	(generator "pcbnew")
	(generator_version "10.0")
	(general
		(thickness 1.6)
		(legacy_teardrops no)
	)
	(paper "A4")
	(title_block
		(title "baseboard — 13948-1b.1110WZS1818.brd")
		(comment 1 "Honey Badger (Wiwynn) / footprints 2401-2408 of 2523")
	)
	(layers
		(0 "F.Cu" signal "TOP")
		(4 "In1.Cu" signal "L2GND")
		(6 "In2.Cu" signal "L3")
		(8 "In3.Cu" signal "L4VCC")
		(10 "In4.Cu" signal "L5VCC")
		(12 "In5.Cu" signal "L6")
		(14 "In6.Cu" signal "L7GND")
		(2 "B.Cu" signal "BOTTOM")
		(9 "F.Adhes" user "F.Adhesive")
		(11 "B.Adhes" user "B.Adhesive")
		(13 "F.Paste" user "Package Geometry/Pastemask Top")
		(15 "B.Paste" user "Package Geometry/Pastemask Bottom")
		(5 "F.SilkS" user "Ref Des/Silkscreen Top")
		(7 "B.SilkS" user "Ref Des/Silkscreen Bottom")
		(1 "F.Mask" user "Board Geometry/Soldermask Top")
		(3 "B.Mask" user "Board Geometry/Soldermask Bottom")
		(17 "Dwgs.User" user "User.Drawings")
		(19 "Cmts.User" user "User.Comments")
		(21 "Eco1.User" user "User.Eco1")
		(23 "Eco2.User" user "User.Eco2")
		(25 "Edge.Cuts" user "Board Geometry/Outline")
		(27 "Margin" user)
		(31 "F.CrtYd" user "Package Geometry/Place Bound Top")
		(29 "B.CrtYd" user "Package Geometry/Place Bound Bottom")
		(35 "F.Fab" user "Ref Des/Assembly Top")
		(33 "B.Fab" user "Ref Des/Assembly Bottom")
	)
	(footprint ""
		(layer "B.Cu")
		(at 345.080336 -71.797672 180)
		(property "Reference" "R267"
			(at 0 0 0)
			(layer "B.SilkS")
			(hide yes)
			(effects
				(font
					(size 1.27 1.27)
				)
				(justify mirror)
			)
		)
		(property "Value" "2K2R2J-2-GP"
			(at -0.064008 -3.993896 180)
			(unlocked yes)
			(layer "B.Fab")
			(hide yes)
			(effects
				(font
					(size 1.016 1.016)
					(thickness 0.1524)
				)
				(justify mirror)
			)
		)
		(property "Device Type" "R402H16"
			(at -0.064008 -5.517896 180)
			(unlocked yes)
			(layer "B.Fab")
			(hide yes)
			(effects
				(font
					(size 1.016 1.016)
					(thickness 0.1524)
				)
				(justify mirror)
			)
		)
		(duplicate_pad_numbers_are_jumpers no)
		(fp_line
			(start 0.508 -0.9398)
			(end 0.508 0.9398)
			(stroke
				(width 0.1524)
				(type default)
			)
			(layer "B.SilkS")
		)
		(fp_line
			(start -0.508 -0.9398)
			(end 0.508 -0.9398)
			(stroke
				(width 0.1524)
				(type default)
			)
			(layer "B.SilkS")
		)
		(fp_rect
			(start 0.508 0.9398)
			(end -0.508 -0.9398)
			(stroke
				(width 0)
				(type default)
			)
			(fill no)
			(layer "B.CrtYd")
		)
		(fp_rect
			(start 0.508 0.9398)
			(end -0.508 -0.9398)
			(stroke
				(width 0)
				(type default)
			)
			(fill no)
			(layer "B.Fab")
		)
		(pad "1" smd custom
			(at 0 -0.4445)
			(size 0.1397 0.1397)
			(layers "B.Cu" "B.Mask" "B.Paste")
			(net "FLA_WPN")
			(options
				(clearance outline)
				(anchor circle)
			)
			(primitives
				(gr_poly
					(pts
						(arc
							(start -0.1778 0.2794)
							(mid -0.249642 0.249642)
							(end -0.2794 0.1778)
						)
						(arc
							(start -0.2794 -0.1778)
							(mid -0.249642 -0.249642)
							(end -0.1778 -0.2794)
						)
						(arc
							(start 0.1778 -0.2794)
							(mid 0.249642 -0.249642)
							(end 0.2794 -0.1778)
						)
						(arc
							(start 0.2794 0.1778)
							(mid 0.249642 0.249642)
							(end 0.1778 0.2794)
						)
					)
					(width 0)
					(fill yes)
				)
			)
		)
		(pad "2" smd custom
			(at 0 0.4445)
			(size 0.1397 0.1397)
			(layers "B.Cu" "B.Mask" "B.Paste")
			(net "GND")
			(options
				(clearance outline)
				(anchor circle)
			)
			(primitives
				(gr_poly
					(pts
						(arc
							(start -0.1778 0.2794)
							(mid -0.249642 0.249642)
							(end -0.2794 0.1778)
						)
						(arc
							(start -0.2794 -0.1778)
							(mid -0.249642 -0.249642)
							(end -0.1778 -0.2794)
						)
						(arc
							(start 0.1778 -0.2794)
							(mid 0.249642 -0.249642)
							(end 0.2794 -0.1778)
						)
						(arc
							(start 0.2794 0.1778)
							(mid 0.249642 0.249642)
							(end 0.1778 0.2794)
						)
					)
					(width 0)
					(fill yes)
				)
			)
		)
	)
	(footprint ""
		(layer "B.Cu")
		(at 30.811216 -202.36688 -90)
		(property "Reference" "C323"
			(at 0 0 90)
			(layer "B.SilkS")
			(hide yes)
			(effects
				(font
					(size 1.27 1.27)
				)
				(justify mirror)
			)
		)
		(property "Value" "SCD1U16V2KX-3GP"
			(at -1.1811 -2.7051 270)
			(unlocked yes)
			(layer "B.Fab")
			(hide yes)
			(effects
				(font
					(size 1.016 1.016)
					(thickness 0.1524)
				)
				(justify mirror)
			)
		)
		(property "Device Type" "C402H22"
			(at -1.1811 -4.2291 270)
			(unlocked yes)
			(layer "B.Fab")
			(hide yes)
			(effects
				(font
					(size 1.016 1.016)
					(thickness 0.1524)
				)
				(justify mirror)
			)
		)
		(duplicate_pad_numbers_are_jumpers no)
		(fp_rect
			(start 0.4318 0.9525)
			(end -0.4318 -0.9525)
			(stroke
				(width 0)
				(type default)
			)
			(fill no)
			(layer "B.CrtYd")
		)
		(fp_rect
			(start 0.4318 0.9525)
			(end -0.4318 -0.9525)
			(stroke
				(width 0)
				(type default)
			)
			(fill no)
			(layer "B.Fab")
		)
		(pad "1" smd custom
			(at 0 -0.4445 90)
			(size 0.1524 0.1524)
			(layers "B.Cu" "B.Mask" "B.Paste")
			(net "P3V3_STBY")
			(options
				(clearance outline)
				(anchor circle)
			)
			(primitives
				(gr_poly
					(pts
						(arc
							(start 0.3048 0.2032)
							(mid 0.275042 0.275042)
							(end 0.2032 0.3048)
						)
						(arc
							(start -0.2032 0.3048)
							(mid -0.275042 0.275042)
							(end -0.3048 0.2032)
						)
						(arc
							(start -0.3048 -0.2032)
							(mid -0.275042 -0.275042)
							(end -0.2032 -0.3048)
						)
						(arc
							(start 0.2032 -0.3048)
							(mid 0.275042 -0.275042)
							(end 0.3048 -0.2032)
						)
					)
					(width 0)
					(fill yes)
				)
			)
		)
		(pad "2" smd custom
			(at 0 0.4445 90)
			(size 0.1524 0.1524)
			(layers "B.Cu" "B.Mask" "B.Paste")
			(net "GND")
			(options
				(clearance outline)
				(anchor circle)
			)
			(primitives
				(gr_poly
					(pts
						(arc
							(start 0.3048 0.2032)
							(mid 0.275042 0.275042)
							(end 0.2032 0.3048)
						)
						(arc
							(start -0.2032 0.3048)
							(mid -0.275042 0.275042)
							(end -0.3048 0.2032)
						)
						(arc
							(start -0.3048 -0.2032)
							(mid -0.275042 -0.275042)
							(end -0.2032 -0.3048)
						)
						(arc
							(start 0.2032 -0.3048)
							(mid 0.275042 -0.275042)
							(end 0.3048 -0.2032)
						)
					)
					(width 0)
					(fill yes)
				)
			)
		)
	)
	(footprint ""
		(layer "B.Cu")
		(at 107.195366 -41.91 90)
		(property "Reference" "SC1052"
			(at 0 0 90)
			(layer "B.SilkS")
			(hide yes)
			(effects
				(font
					(size 1.27 1.27)
				)
				(justify mirror)
			)
		)
		(property "Value" "SCD1U16V2KX-3GP"
			(at -1.1811 -2.7051 90)
			(unlocked yes)
			(layer "B.Fab")
			(hide yes)
			(effects
				(font
					(size 1.016 1.016)
					(thickness 0.1524)
				)
				(justify mirror)
			)
		)
		(property "Device Type" "C402H22"
			(at -1.1811 -4.2291 90)
			(unlocked yes)
			(layer "B.Fab")
			(hide yes)
			(effects
				(font
					(size 1.016 1.016)
					(thickness 0.1524)
				)
				(justify mirror)
			)
		)
		(duplicate_pad_numbers_are_jumpers no)
		(fp_rect
			(start 0.4318 0.9525)
			(end -0.4318 -0.9525)
			(stroke
				(width 0)
				(type default)
			)
			(fill no)
			(layer "B.CrtYd")
		)
		(fp_rect
			(start 0.4318 0.9525)
			(end -0.4318 -0.9525)
			(stroke
				(width 0)
				(type default)
			)
			(fill no)
			(layer "B.Fab")
		)
		(pad "1" smd custom
			(at 0 -0.4445 270)
			(size 0.1524 0.1524)
			(layers "B.Cu" "B.Mask" "B.Paste")
			(net "P0V955_C")
			(options
				(clearance outline)
				(anchor circle)
			)
			(primitives
				(gr_poly
					(pts
						(arc
							(start 0.3048 0.2032)
							(mid 0.275042 0.275042)
							(end 0.2032 0.3048)
						)
						(arc
							(start -0.2032 0.3048)
							(mid -0.275042 0.275042)
							(end -0.3048 0.2032)
						)
						(arc
							(start -0.3048 -0.2032)
							(mid -0.275042 -0.275042)
							(end -0.2032 -0.3048)
						)
						(arc
							(start 0.2032 -0.3048)
							(mid 0.275042 -0.275042)
							(end 0.3048 -0.2032)
						)
					)
					(width 0)
					(fill yes)
				)
			)
		)
		(pad "2" smd custom
			(at 0 0.4445 270)
			(size 0.1524 0.1524)
			(layers "B.Cu" "B.Mask" "B.Paste")
			(net "GND")
			(options
				(clearance outline)
				(anchor circle)
			)
			(primitives
				(gr_poly
					(pts
						(arc
							(start 0.3048 0.2032)
							(mid 0.275042 0.275042)
							(end 0.2032 0.3048)
						)
						(arc
							(start -0.2032 0.3048)
							(mid -0.275042 0.275042)
							(end -0.3048 0.2032)
						)
						(arc
							(start -0.3048 -0.2032)
							(mid -0.275042 -0.275042)
							(end -0.2032 -0.3048)
						)
						(arc
							(start 0.2032 -0.3048)
							(mid 0.275042 -0.275042)
							(end 0.3048 -0.2032)
						)
					)
					(width 0)
					(fill yes)
				)
			)
		)
	)
	(footprint ""
		(layer "B.Cu")
		(at 310.896 -183.515 -90)
		(property "Reference" "SR944"
			(at 0 0 90)
			(layer "B.SilkS")
			(hide yes)
			(effects
				(font
					(size 1.27 1.27)
				)
				(justify mirror)
			)
		)
		(property "Value" "4K75R2F-1-GP"
			(at -0.064008 -3.993896 270)
			(unlocked yes)
			(layer "B.Fab")
			(hide yes)
			(effects
				(font
					(size 1.016 1.016)
					(thickness 0.1524)
				)
				(justify mirror)
			)
		)
		(property "Device Type" "R402H16"
			(at -0.064008 -5.517896 270)
			(unlocked yes)
			(layer "B.Fab")
			(hide yes)
			(effects
				(font
					(size 1.016 1.016)
					(thickness 0.1524)
				)
				(justify mirror)
			)
		)
		(duplicate_pad_numbers_are_jumpers no)
		(fp_line
			(start -0.508 -0.9398)
			(end 0.508 -0.9398)
			(stroke
				(width 0.1524)
				(type default)
			)
			(layer "B.SilkS")
		)
		(fp_line
			(start 0.508 -0.9398)
			(end 0.508 0.9398)
			(stroke
				(width 0.1524)
				(type default)
			)
			(layer "B.SilkS")
		)
		(fp_rect
			(start 0.508 0.9398)
			(end -0.508 -0.9398)
			(stroke
				(width 0)
				(type default)
			)
			(fill no)
			(layer "B.CrtYd")
		)
		(fp_rect
			(start 0.508 0.9398)
			(end -0.508 -0.9398)
			(stroke
				(width 0)
				(type default)
			)
			(fill no)
			(layer "B.Fab")
		)
		(pad "1" smd custom
			(at 0 -0.4445 90)
			(size 0.1397 0.1397)
			(layers "B.Cu" "B.Mask" "B.Paste")
			(net "P3V3_STBY")
			(options
				(clearance outline)
				(anchor circle)
			)
			(primitives
				(gr_poly
					(pts
						(arc
							(start -0.1778 0.2794)
							(mid -0.249642 0.249642)
							(end -0.2794 0.1778)
						)
						(arc
							(start -0.2794 -0.1778)
							(mid -0.249642 -0.249642)
							(end -0.1778 -0.2794)
						)
						(arc
							(start 0.1778 -0.2794)
							(mid 0.249642 -0.249642)
							(end 0.2794 -0.1778)
						)
						(arc
							(start 0.2794 0.1778)
							(mid 0.249642 0.249642)
							(end 0.1778 0.2794)
						)
					)
					(width 0)
					(fill yes)
				)
			)
		)
		(pad "2" smd custom
			(at 0 0.4445 90)
			(size 0.1397 0.1397)
			(layers "B.Cu" "B.Mask" "B.Paste")
			(net "BMC_FW_DET_BOARD_VER_0")
			(options
				(clearance outline)
				(anchor circle)
			)
			(primitives
				(gr_poly
					(pts
						(arc
							(start -0.1778 0.2794)
							(mid -0.249642 0.249642)
							(end -0.2794 0.1778)
						)
						(arc
							(start -0.2794 -0.1778)
							(mid -0.249642 -0.249642)
							(end -0.1778 -0.2794)
						)
						(arc
							(start 0.1778 -0.2794)
							(mid 0.249642 -0.249642)
							(end 0.2794 -0.1778)
						)
						(arc
							(start 0.2794 0.1778)
							(mid 0.249642 0.249642)
							(end 0.1778 0.2794)
						)
					)
					(width 0)
					(fill yes)
				)
			)
		)
	)
	(footprint ""
		(layer "B.Cu")
		(at 124.530612 -222.377 -90)
		(property "Reference" "SR870"
			(at 0 0 90)
			(layer "B.SilkS")
			(hide yes)
			(effects
				(font
					(size 1.27 1.27)
				)
				(justify mirror)
			)
		)
		(property "Value" "0R5J-5-GP"
			(at 0 -8.9535 270)
			(unlocked yes)
			(layer "B.Fab")
			(hide yes)
			(effects
				(font
					(size 1.27 1.016)
					(thickness 0.1524)
				)
				(justify mirror)
			)
		)
		(property "Device Type" "R805H24"
			(at 0 -10.6299 270)
			(unlocked yes)
			(layer "B.Fab")
			(hide yes)
			(effects
				(font
					(size 1.27 1.016)
					(thickness 0.1524)
				)
				(justify mirror)
			)
		)
		(duplicate_pad_numbers_are_jumpers no)
		(fp_line
			(start -0.889 1.7018)
			(end -0.889 -0.508)
			(stroke
				(width 0.1524)
				(type default)
			)
			(layer "B.SilkS")
		)
		(fp_line
			(start 0.889 1.7018)
			(end -0.889 1.7018)
			(stroke
				(width 0.1524)
				(type default)
			)
			(layer "B.SilkS")
		)
		(fp_line
			(start 0.889 0.0762)
			(end 0.889 1.7018)
			(stroke
				(width 0.1524)
				(type default)
			)
			(layer "B.SilkS")
		)
		(fp_line
			(start -0.889 -1.7018)
			(end -0.889 -0.381)
			(stroke
				(width 0.1524)
				(type default)
			)
			(layer "B.SilkS")
		)
		(fp_line
			(start -0.889 -1.7018)
			(end 0.889 -1.7018)
			(stroke
				(width 0.1524)
				(type default)
			)
			(layer "B.SilkS")
		)
		(fp_line
			(start 0.889 -1.7018)
			(end 0.889 0.2794)
			(stroke
				(width 0.1524)
				(type default)
			)
			(layer "B.SilkS")
		)
		(fp_poly
			(pts
				(xy -0.9652 -1.778) (xy -0.9652 1.778) (xy 0.9652 1.778) (xy 0.9652 -1.778)
			)
			(stroke
				(width 0)
				(type default)
			)
			(fill no)
			(layer "B.CrtYd")
		)
		(fp_rect
			(start 0.9652 1.778)
			(end -0.9652 -1.778)
			(stroke
				(width 0)
				(type default)
			)
			(fill no)
			(layer "B.Fab")
		)
		(pad "1" smd rect
			(at 0 -0.9652 90)
			(size 1.397 1.143)
			(layers "B.Cu" "B.Mask" "B.Paste")
			(net "P1V26_STBY")
		)
		(pad "2" smd rect
			(at 0 0.9652 90)
			(size 1.397 1.143)
			(layers "B.Cu" "B.Mask" "B.Paste")
			(net "1.2V_REDV")
		)
	)
	(footprint ""
		(layer "B.Cu")
		(at 106.103166 -36.957)
		(property "Reference" "STP53"
			(at 0 0 0)
			(layer "B.SilkS")
			(hide yes)
			(effects
				(font
					(size 1.27 1.27)
				)
				(justify mirror)
			)
		)
		(property "Value" "TPAD28"
			(at -0.0127 -1.8034 0)
			(unlocked yes)
			(layer "B.Fab")
			(hide yes)
			(effects
				(font
					(size 1.016 1.016)
					(thickness 0.1524)
				)
				(justify mirror)
			)
		)
		(property "Device Type" "TPAD28"
			(at -0.0127 -3.3274 0)
			(unlocked yes)
			(layer "B.Fab")
			(hide yes)
			(effects
				(font
					(size 1.016 1.016)
					(thickness 0.1524)
				)
				(justify mirror)
			)
		)
		(duplicate_pad_numbers_are_jumpers no)
		(fp_poly
			(pts
				(arc
					(start 0.3556 0)
					(mid -0.3556 0)
					(end 0.3556 0)
				)
			)
			(stroke
				(width 0)
				(type default)
			)
			(fill no)
			(layer "B.CrtYd")
		)
		(fp_poly
			(pts
				(arc
					(start 0.6096 0)
					(mid -0.6096 0)
					(end 0.6096 0)
				)
			)
			(stroke
				(width 0)
				(type default)
			)
			(fill no)
			(layer "B.Fab")
		)
		(pad "1" smd circle
			(at 0 0 180)
			(size 0.7112 0.7112)
			(layers "B.Cu" "B.Mask" "B.Paste")
			(net "SPARE3")
		)
	)
	(footprint ""
		(layer "B.Cu")
		(at 274.193 -171.577 90)
		(property "Reference" "R306"
			(at 0 0 90)
			(layer "B.SilkS")
			(hide yes)
			(effects
				(font
					(size 1.27 1.27)
				)
				(justify mirror)
			)
		)
		(property "Value" "10KR2F-2-GP"
			(at -0.064008 -3.993896 90)
			(unlocked yes)
			(layer "B.Fab")
			(hide yes)
			(effects
				(font
					(size 1.016 1.016)
					(thickness 0.1524)
				)
				(justify mirror)
			)
		)
		(property "Device Type" "R402H16"
			(at -0.064008 -5.517896 90)
			(unlocked yes)
			(layer "B.Fab")
			(hide yes)
			(effects
				(font
					(size 1.016 1.016)
					(thickness 0.1524)
				)
				(justify mirror)
			)
		)
		(duplicate_pad_numbers_are_jumpers no)
		(fp_line
			(start 0.508 -0.9398)
			(end 0.508 0.9398)
			(stroke
				(width 0.1524)
				(type default)
			)
			(layer "B.SilkS")
		)
		(fp_line
			(start -0.508 -0.9398)
			(end 0.508 -0.9398)
			(stroke
				(width 0.1524)
				(type default)
			)
			(layer "B.SilkS")
		)
		(fp_rect
			(start 0.508 0.9398)
			(end -0.508 -0.9398)
			(stroke
				(width 0)
				(type default)
			)
			(fill no)
			(layer "B.CrtYd")
		)
		(fp_rect
			(start 0.508 0.9398)
			(end -0.508 -0.9398)
			(stroke
				(width 0)
				(type default)
			)
			(fill no)
			(layer "B.Fab")
		)
		(pad "1" smd custom
			(at 0 -0.4445 270)
			(size 0.1397 0.1397)
			(layers "B.Cu" "B.Mask" "B.Paste")
			(net "P3V3_STBY")
			(options
				(clearance outline)
				(anchor circle)
			)
			(primitives
				(gr_poly
					(pts
						(arc
							(start -0.1778 0.2794)
							(mid -0.249642 0.249642)
							(end -0.2794 0.1778)
						)
						(arc
							(start -0.2794 -0.1778)
							(mid -0.249642 -0.249642)
							(end -0.1778 -0.2794)
						)
						(arc
							(start 0.1778 -0.2794)
							(mid 0.249642 -0.249642)
							(end 0.2794 -0.1778)
						)
						(arc
							(start 0.2794 0.1778)
							(mid 0.249642 0.249642)
							(end 0.1778 0.2794)
						)
					)
					(width 0)
					(fill yes)
				)
			)
		)
		(pad "2" smd custom
			(at 0 0.4445 270)
			(size 0.1397 0.1397)
			(layers "B.Cu" "B.Mask" "B.Paste")
			(net "BMC_10G_SDA_2")
			(options
				(clearance outline)
				(anchor circle)
			)
			(primitives
				(gr_poly
					(pts
						(arc
							(start -0.1778 0.2794)
							(mid -0.249642 0.249642)
							(end -0.2794 0.1778)
						)
						(arc
							(start -0.2794 -0.1778)
							(mid -0.249642 -0.249642)
							(end -0.1778 -0.2794)
						)
						(arc
							(start 0.1778 -0.2794)
							(mid 0.249642 -0.249642)
							(end 0.2794 -0.1778)
						)
						(arc
							(start 0.2794 0.1778)
							(mid 0.249642 0.249642)
							(end 0.1778 0.2794)
						)
					)
					(width 0)
					(fill yes)
				)
			)
		)
	)
	(footprint ""
		(layer "B.Cu")
		(at 276.733 -166.37 90)
		(property "Reference" "R540"
			(at 0 0 90)
			(layer "B.SilkS")
			(hide yes)
			(effects
				(font
					(size 1.27 1.27)
				)
				(justify mirror)
			)
		)
		(property "Value" "0R2J-2-GP"
			(at -0.064008 -3.993896 90)
			(unlocked yes)
			(layer "B.Fab")
			(hide yes)
			(effects
				(font
					(size 1.016 1.016)
					(thickness 0.1524)
				)
				(justify mirror)
			)
		)
		(property "Device Type" "R402H16"
			(at -0.064008 -5.517896 90)
			(unlocked yes)
			(layer "B.Fab")
			(hide yes)
			(effects
				(font
					(size 1.016 1.016)
					(thickness 0.1524)
				)
				(justify mirror)
			)
		)
		(duplicate_pad_numbers_are_jumpers no)
		(fp_line
			(start 0.508 -0.9398)
			(end 0.508 0.9398)
			(stroke
				(width 0.1524)
				(type default)
			)
			(layer "B.SilkS")
		)
		(fp_line
			(start -0.508 -0.9398)
			(end 0.508 -0.9398)
			(stroke
				(width 0.1524)
				(type default)
			)
			(layer "B.SilkS")
		)
		(fp_rect
			(start 0.508 0.9398)
			(end -0.508 -0.9398)
			(stroke
				(width 0)
				(type default)
			)
			(fill no)
			(layer "B.CrtYd")
		)
		(fp_rect
			(start 0.508 0.9398)
			(end -0.508 -0.9398)
			(stroke
				(width 0)
				(type default)
			)
			(fill no)
			(layer "B.Fab")
		)
		(pad "1" smd custom
			(at 0 -0.4445 270)
			(size 0.1397 0.1397)
			(layers "B.Cu" "B.Mask" "B.Paste")
			(net "BMC_1V8_C_EN")
			(options
				(clearance outline)
				(anchor circle)
			)
			(primitives
				(gr_poly
					(pts
						(arc
							(start -0.1778 0.2794)
							(mid -0.249642 0.249642)
							(end -0.2794 0.1778)
						)
						(arc
							(start -0.2794 -0.1778)
							(mid -0.249642 -0.249642)
							(end -0.1778 -0.2794)
						)
						(arc
							(start 0.1778 -0.2794)
							(mid 0.249642 -0.249642)
							(end 0.2794 -0.1778)
						)
						(arc
							(start 0.2794 0.1778)
							(mid 0.249642 0.249642)
							(end 0.1778 0.2794)
						)
					)
					(width 0)
					(fill yes)
				)
			)
		)
		(pad "2" smd custom
			(at 0 0.4445 270)
			(size 0.1397 0.1397)
			(layers "B.Cu" "B.Mask" "B.Paste")
			(net "BMC_1V8_C_EN_R")
			(options
				(clearance outline)
				(anchor circle)
			)
			(primitives
				(gr_poly
					(pts
						(arc
							(start -0.1778 0.2794)
							(mid -0.249642 0.249642)
							(end -0.2794 0.1778)
						)
						(arc
							(start -0.2794 -0.1778)
							(mid -0.249642 -0.249642)
							(end -0.1778 -0.2794)
						)
						(arc
							(start 0.1778 -0.2794)
							(mid 0.249642 -0.249642)
							(end 0.2794 -0.1778)
						)
						(arc
							(start 0.2794 0.1778)
							(mid 0.249642 0.249642)
							(end 0.1778 0.2794)
						)
					)
					(width 0)
					(fill yes)
				)
			)
		)
	)
)
